(kicad_pcb
	(version 20260206)
	(generator "pcbnew")
	(generator_version "10.0")
	(general
		(thickness 1.6)
		(legacy_teardrops no)
	)
	(paper "A4")
	(title_block
		(title "Wiwynn_Tioga_Pass_MB.brd")
		(comment 1 "Tioga Pass / footprint 190 of 4770 (U2D1), pads 2518-2624 of 3647")
	)
	(layers
		(0 "F.Cu" signal "TOP")
		(4 "In1.Cu" signal "L2GND")
		(6 "In2.Cu" signal "L3")
		(8 "In3.Cu" signal "L4GND")
		(10 "In4.Cu" signal "L5")
		(12 "In5.Cu" signal "L6GND")
		(14 "In6.Cu" signal "L7VCC")
		(16 "In7.Cu" signal "L8VCC")
		(18 "In8.Cu" signal "L9GND")
		(20 "In9.Cu" signal "L10")
		(22 "In10.Cu" signal "L11GND")
		(24 "In11.Cu" signal "L12")
		(26 "In12.Cu" signal "L13GND")
		(2 "B.Cu" signal "BOTTOM")
		(9 "F.Adhes" user "F.Adhesive")
		(11 "B.Adhes" user "B.Adhesive")
		(13 "F.Paste" user "Package Geometry/Pastemask Top")
		(15 "B.Paste" user "Package Geometry/Pastemask Bottom")
		(5 "F.SilkS" user "Ref Des/Silkscreen Top")
		(7 "B.SilkS" user "Ref Des/Silkscreen Bottom")
		(1 "F.Mask" user "Board Geometry/Soldermask Top")
		(3 "B.Mask" user "Board Geometry/Soldermask Bottom")
		(17 "Dwgs.User" user "User.Drawings")
		(19 "Cmts.User" user "User.Comments")
		(21 "Eco1.User" user "User.Eco1")
		(23 "Eco2.User" user "User.Eco2")
		(25 "Edge.Cuts" user "Board Geometry/Outline")
		(27 "Margin" user)
		(31 "F.CrtYd" user "Package Geometry/Place Bound Top")
		(29 "B.CrtYd" user "Package Geometry/Place Bound Bottom")
		(35 "F.Fab" user "Ref Des/Assembly Top")
		(33 "B.Fab" user "Ref Des/Assembly Bottom")
	)
	(footprint ""
		(layer "F.Cu")
		(at 104.99979 -76.550012 180)
		(property "Reference" "U2D1"
			(at 25.19299 30.484318 0)
			(unlocked yes)
			(layer "F.SilkS")
			(effects
				(font
					(size 0.7874 0.5842)
					(thickness 0.1524)
				)
			)
		)
		(property "Value" ""
			(at 0 0 180)
			(layer "F.Fab")
			(effects
				(font
					(size 1.27 1.27)
				)
			)
		)
		(duplicate_pad_numbers_are_jumpers no)
		(pad "DP73" smd circle
			(at 26.090118 19.159474)
			(size 0.4318 0.4318)
			(layers "F.Cu" "F.Mask" "F.Paste")
			(net "M_K_DQ<26>")
		)
		(pad "DP75" smd circle
			(at 27.806904 19.159474)
			(size 0.4318 0.4318)
			(layers "F.Cu" "F.Mask" "F.Paste")
			(net "M_K_DQS_DN<12>")
		)
		(pad "DP77" smd circle
			(at 29.523944 19.159474)
			(size 0.4318 0.4318)
			(layers "F.Cu" "F.Mask" "F.Paste")
			(net "M_K_DQ<28>")
		)
		(pad "DP79" smd circle
			(at 31.240984 19.159474)
			(size 0.4318 0.4318)
			(layers "F.Cu" "F.Mask" "F.Paste")
			(net "M_K_DQS_DP<11>")
		)
		(pad "DP81" smd circle
			(at 32.958024 19.159474)
			(size 0.4318 0.4318)
			(layers "F.Cu" "F.Mask" "F.Paste")
			(net "GND")
		)
		(pad "DP83" smd circle
			(at 34.675064 19.159474)
			(size 0.4318 0.4318)
			(layers "F.Cu" "F.Mask" "F.Paste")
			(net "GND")
		)
		(pad "DP85" smd custom
			(at 36.392104 19.159474 270)
			(size 0.10795 0.10795)
			(layers "F.Cu" "F.Mask" "F.Paste")
			(net "M_K_DQS_DP<1>")
			(options
				(clearance outline)
				(anchor circle)
			)
			(primitives
				(gr_poly
					(pts
						(arc
							(start 0.2159 -0.0381)
							(mid 0 -0.254)
							(end -0.2159 -0.0381)
						)
						(arc
							(start -0.2159 0.0381)
							(mid 0 0.254)
							(end 0.2159 0.0381)
						)
					)
					(width 0)
					(fill yes)
				)
			)
		)
		(pad "DR2" smd custom
			(at -36.392104 21.455126 90)
			(size 0.10795 0.10795)
			(layers "F.Cu" "F.Mask" "F.Paste")
			(net "PVCCIO_CPU1")
			(options
				(clearance outline)
				(anchor circle)
			)
			(primitives
				(gr_poly
					(pts
						(arc
							(start 0.2159 -0.0381)
							(mid 0 -0.254)
							(end -0.2159 -0.0381)
						)
						(arc
							(start -0.2159 0.0381)
							(mid 0 0.254)
							(end 0.2159 0.0381)
						)
					)
					(width 0)
					(fill yes)
				)
			)
		)
		(pad "DR4" smd circle
			(at -34.675064 21.455126)
			(size 0.4318 0.4318)
			(layers "F.Cu" "F.Mask" "F.Paste")
			(net "TP_P3E_CPU1_PE1_RSR3_TXP<8>")
		)
		(pad "DR6" smd circle
			(at -32.958024 21.455126)
			(size 0.4318 0.4318)
			(layers "F.Cu" "F.Mask" "F.Paste")
			(net "GND")
		)
		(pad "DR8" smd circle
			(at -31.240984 21.455126)
			(size 0.4318 0.4318)
			(layers "F.Cu" "F.Mask" "F.Paste")
			(net "P3E_CPU1_PE3_MP_TXN<7>")
		)
		(pad "DR10" smd circle
			(at -29.523944 21.455126)
			(size 0.4318 0.4318)
			(layers "F.Cu" "F.Mask" "F.Paste")
			(net "PVCCIO_CPU1")
		)
		(pad "DR12" smd circle
			(at -27.806904 21.455126)
			(size 0.4318 0.4318)
			(layers "F.Cu" "F.Mask" "F.Paste")
			(net "TP_P3E_CPU1_PE1_RSR3_RXP<10>")
		)
		(pad "DR14" smd circle
			(at -26.090118 21.455126)
			(size 0.4318 0.4318)
			(layers "F.Cu" "F.Mask" "F.Paste")
			(net "P3E_CPU1_PE3_MP_RXN<5>")
		)
		(pad "DR16" smd circle
			(at -24.373078 21.455126)
			(size 0.4318 0.4318)
			(layers "F.Cu" "F.Mask" "F.Paste")
			(net "P3E_CPU1_PE3_MP_RXN<4>")
		)
		(pad "DR18" smd circle
			(at -22.656038 21.455126)
			(size 0.4318 0.4318)
			(layers "F.Cu" "F.Mask" "F.Paste")
			(net "P3E_CPU1_PE3_MP_RXP<3>")
		)
		(pad "DR20" smd circle
			(at -20.938998 21.455126)
			(size 0.4318 0.4318)
			(layers "F.Cu" "F.Mask" "F.Paste")
			(net "GND")
		)
		(pad "DR22" smd circle
			(at -19.221958 21.455126)
			(size 0.4318 0.4318)
			(layers "F.Cu" "F.Mask" "F.Paste")
			(net "GND")
		)
		(pad "DR24" smd circle
			(at -17.504918 21.455126)
			(size 0.4318 0.4318)
			(layers "F.Cu" "F.Mask" "F.Paste")
			(net "GND")
		)
		(pad "DR26" smd circle
			(at -15.787878 21.455126)
			(size 0.4318 0.4318)
			(layers "F.Cu" "F.Mask" "F.Paste")
			(net "GND")
		)
		(pad "DR28" smd circle
			(at -14.071092 21.455126)
			(size 0.4318 0.4318)
			(layers "F.Cu" "F.Mask" "F.Paste")
			(net "GND")
		)
		(pad "DR30" smd circle
			(at -12.354052 21.455126)
			(size 0.4318 0.4318)
			(layers "F.Cu" "F.Mask" "F.Paste")
			(net "GND")
		)
		(pad "DR32" smd circle
			(at -10.637012 21.455126)
			(size 0.4318 0.4318)
			(layers "F.Cu" "F.Mask" "F.Paste")
			(net "GND")
		)
		(pad "DR34" smd circle
			(at -8.919972 21.455126)
			(size 0.4318 0.4318)
			(layers "F.Cu" "F.Mask" "F.Paste")
			(net "GND")
		)
		(pad "DR36" smd circle
			(at -7.202932 21.455126)
			(size 0.4318 0.4318)
			(layers "F.Cu" "F.Mask" "F.Paste")
			(net "GND")
		)
		(pad "DR38" smd circle
			(at -5.485892 21.455126)
			(size 0.4318 0.4318)
			(layers "F.Cu" "F.Mask" "F.Paste")
			(net "GND")
		)
		(pad "DR40" smd circle
			(at -3.769106 21.455126)
			(size 0.4318 0.4318)
			(layers "F.Cu" "F.Mask" "F.Paste")
			(net "GND")
		)
		(pad "DR42" smd circle
			(at -2.052066 21.455126)
			(size 0.4318 0.4318)
			(layers "F.Cu" "F.Mask" "F.Paste")
			(net "GND")
		)
		(pad "DR44" smd circle
			(at 1.193546 19.655028)
			(size 0.508 0.508)
			(layers "F.Cu" "F.Mask" "F.Paste")
			(net "TP_CPU1_RSVD_28")
		)
		(pad "DR46" smd circle
			(at 2.910586 19.655028)
			(size 0.4318 0.4318)
			(layers "F.Cu" "F.Mask" "F.Paste")
			(net "M_L_CS_N<2>")
		)
		(pad "DR48" smd circle
			(at 4.627626 19.655028)
			(size 0.4318 0.4318)
			(layers "F.Cu" "F.Mask" "F.Paste")
			(net "M_L_MA<17>")
		)
		(pad "DR50" smd circle
			(at 6.344412 19.655028)
			(size 0.4318 0.4318)
			(layers "F.Cu" "F.Mask" "F.Paste")
			(net "M_L_ODT<0>")
		)
		(pad "DR52" smd circle
			(at 8.061452 19.655028)
			(size 0.4318 0.4318)
			(layers "F.Cu" "F.Mask" "F.Paste")
			(net "M_L_MA<15>")
		)
		(pad "DR54" smd circle
			(at 9.778492 19.655028)
			(size 0.4318 0.4318)
			(layers "F.Cu" "F.Mask" "F.Paste")
			(net "M_L_CLK_DN<1>")
		)
		(pad "DR56" smd circle
			(at 11.495532 19.655028)
			(size 0.4318 0.4318)
			(layers "F.Cu" "F.Mask" "F.Paste")
			(net "M_L_CLK_DP<3>")
		)
		(pad "DR58" smd circle
			(at 13.212572 19.655028)
			(size 0.4318 0.4318)
			(layers "F.Cu" "F.Mask" "F.Paste")
			(net "M_L_MA<3>")
		)
		(pad "DR60" smd circle
			(at 14.929612 19.655028)
			(size 0.4318 0.4318)
			(layers "F.Cu" "F.Mask" "F.Paste")
			(net "M_L_MA<11>")
		)
		(pad "DR62" smd circle
			(at 16.646398 19.655028)
			(size 0.4318 0.4318)
			(layers "F.Cu" "F.Mask" "F.Paste")
			(net "M_L_ACT_N")
		)
		(pad "DR64" smd circle
			(at 18.363438 19.655028)
			(size 0.4318 0.4318)
			(layers "F.Cu" "F.Mask" "F.Paste")
			(net "M_L_CKE<3>")
		)
		(pad "DR66" smd circle
			(at 20.080478 19.655028)
			(size 0.4318 0.4318)
			(layers "F.Cu" "F.Mask" "F.Paste")
			(net "GND")
		)
		(pad "DR68" smd circle
			(at 21.797518 19.655028)
			(size 0.4318 0.4318)
			(layers "F.Cu" "F.Mask" "F.Paste")
			(net "GND")
		)
		(pad "DR70" smd circle
			(at 23.514558 19.655028)
			(size 0.4318 0.4318)
			(layers "F.Cu" "F.Mask" "F.Paste")
			(net "GND")
		)
		(pad "DR72" smd circle
			(at 25.231598 19.655028)
			(size 0.4318 0.4318)
			(layers "F.Cu" "F.Mask" "F.Paste")
			(net "GND")
		)
		(pad "DR74" smd circle
			(at 26.948384 19.655028)
			(size 0.4318 0.4318)
			(layers "F.Cu" "F.Mask" "F.Paste")
			(net "GND")
		)
		(pad "DR76" smd circle
			(at 28.665424 19.655028)
			(size 0.4318 0.4318)
			(layers "F.Cu" "F.Mask" "F.Paste")
			(net "GND")
		)
		(pad "DR78" smd circle
			(at 30.382464 19.655028)
			(size 0.4318 0.4318)
			(layers "F.Cu" "F.Mask" "F.Paste")
			(net "GND")
		)
		(pad "DR80" smd circle
			(at 32.099504 19.655028)
			(size 0.4318 0.4318)
			(layers "F.Cu" "F.Mask" "F.Paste")
			(net "M_K_DQ<22>")
		)
		(pad "DR82" smd circle
			(at 33.816544 19.655028)
			(size 0.4318 0.4318)
			(layers "F.Cu" "F.Mask" "F.Paste")
			(net "M_K_DQ<19>")
		)
		(pad "DR84" smd circle
			(at 35.533584 19.655028)
			(size 0.4318 0.4318)
			(layers "F.Cu" "F.Mask" "F.Paste")
			(net "M_K_DQ<14>")
		)
		(pad "DT3" smd circle
			(at -35.533584 21.950172)
			(size 0.4318 0.4318)
			(layers "F.Cu" "F.Mask" "F.Paste")
			(net "GND")
		)
		(pad "DT5" smd circle
			(at -33.816544 21.950172)
			(size 0.4318 0.4318)
			(layers "F.Cu" "F.Mask" "F.Paste")
			(net "TP_P3E_CPU1_PE1_RSR3_TXN<8>")
		)
		(pad "DT7" smd circle
			(at -32.099504 21.950172)
			(size 0.4318 0.4318)
			(layers "F.Cu" "F.Mask" "F.Paste")
			(net "TP_P3E_CPU1_PE1_RSR3_TXP<12>")
		)
		(pad "DT9" smd circle
			(at -30.382464 21.950172)
			(size 0.4318 0.4318)
			(layers "F.Cu" "F.Mask" "F.Paste")
			(net "P3E_CPU1_PE3_MP_TXP<6>")
		)
		(pad "DT11" smd circle
			(at -28.665424 21.950172)
			(size 0.4318 0.4318)
			(layers "F.Cu" "F.Mask" "F.Paste")
			(net "TP_P3E_CPU1_PE1_RSR3_RXN<10>")
		)
		(pad "DT13" smd circle
			(at -26.948384 21.950172)
			(size 0.4318 0.4318)
			(layers "F.Cu" "F.Mask" "F.Paste")
			(net "TP_P3E_CPU1_PE1_RSR3_RXN<11>")
		)
		(pad "DT15" smd circle
			(at -25.231598 21.950172)
			(size 0.4318 0.4318)
			(layers "F.Cu" "F.Mask" "F.Paste")
			(net "TP_P3E_CPU1_PE1_RSR3_RXP<15>")
		)
		(pad "DT17" smd circle
			(at -23.514558 21.950172)
			(size 0.4318 0.4318)
			(layers "F.Cu" "F.Mask" "F.Paste")
			(net "GND")
		)
		(pad "DT19" smd circle
			(at -21.797518 21.950172)
			(size 0.4318 0.4318)
			(layers "F.Cu" "F.Mask" "F.Paste")
			(net "P3E_CPU1_PE3_MP_RXN<3>")
		)
		(pad "DT21" smd circle
			(at -20.080478 21.950172)
			(size 0.4318 0.4318)
			(layers "F.Cu" "F.Mask" "F.Paste")
			(net "TP_CPU1_UPI2_RSVD_CC12")
		)
		(pad "DT23" smd circle
			(at -18.363438 21.950172)
			(size 0.4318 0.4318)
			(layers "F.Cu" "F.Mask" "F.Paste")
			(net "M_K_DQS_DP<7>")
		)
		(pad "DT25" smd circle
			(at -16.646398 21.950172)
			(size 0.4318 0.4318)
			(layers "F.Cu" "F.Mask" "F.Paste")
			(net "M_K_DQ<61>")
		)
		(pad "DT27" smd circle
			(at -14.929612 21.950172)
			(size 0.4318 0.4318)
			(layers "F.Cu" "F.Mask" "F.Paste")
			(net "M_K_DQ<51>")
		)
		(pad "DT29" smd circle
			(at -13.212572 21.950172)
			(size 0.4318 0.4318)
			(layers "F.Cu" "F.Mask" "F.Paste")
			(net "M_K_DQS_DP<6>")
		)
		(pad "DT31" smd circle
			(at -11.495532 21.950172)
			(size 0.4318 0.4318)
			(layers "F.Cu" "F.Mask" "F.Paste")
			(net "M_K_DQ<53>")
		)
		(pad "DT33" smd circle
			(at -9.778492 21.950172)
			(size 0.4318 0.4318)
			(layers "F.Cu" "F.Mask" "F.Paste")
			(net "M_K_DQ<43>")
		)
		(pad "DT35" smd circle
			(at -8.061452 21.950172)
			(size 0.4318 0.4318)
			(layers "F.Cu" "F.Mask" "F.Paste")
			(net "M_K_DQS_DP<5>")
		)
		(pad "DT37" smd circle
			(at -6.344412 21.950172)
			(size 0.4318 0.4318)
			(layers "F.Cu" "F.Mask" "F.Paste")
			(net "M_K_DQ<45>")
		)
		(pad "DT39" smd circle
			(at -4.627626 21.950172)
			(size 0.4318 0.4318)
			(layers "F.Cu" "F.Mask" "F.Paste")
			(net "M_L_DQ<35>")
		)
		(pad "DT41" smd circle
			(at -2.910586 21.950172)
			(size 0.4318 0.4318)
			(layers "F.Cu" "F.Mask" "F.Paste")
			(net "M_L_DQS_DP<4>")
		)
		(pad "DT45" smd circle
			(at 2.052066 20.150074)
			(size 0.4318 0.4318)
			(layers "F.Cu" "F.Mask" "F.Paste")
			(net "M_L_CS_N<6>")
		)
		(pad "DT47" smd circle
			(at 3.769106 20.150074)
			(size 0.4318 0.4318)
			(layers "F.Cu" "F.Mask" "F.Paste")
			(net "M_L_C<2>")
		)
		(pad "DT49" smd circle
			(at 5.485892 20.150074)
			(size 0.4318 0.4318)
			(layers "F.Cu" "F.Mask" "F.Paste")
			(net "M_L_ODT<2>")
		)
		(pad "DT51" smd circle
			(at 7.202932 20.150074)
			(size 0.4318 0.4318)
			(layers "F.Cu" "F.Mask" "F.Paste")
			(net "M_L_MA<13>")
		)
		(pad "DT53" smd circle
			(at 8.919972 20.150074)
			(size 0.4318 0.4318)
			(layers "F.Cu" "F.Mask" "F.Paste")
			(net "M_L_CLK_DP<1>")
		)
		(pad "DT55" smd circle
			(at 10.637012 20.150074)
			(size 0.4318 0.4318)
			(layers "F.Cu" "F.Mask" "F.Paste")
			(net "M_L_MA<10>")
		)
		(pad "DT57" smd circle
			(at 12.354052 20.150074)
			(size 0.4318 0.4318)
			(layers "F.Cu" "F.Mask" "F.Paste")
			(net "M_L_CLK_DN<3>")
		)
		(pad "DT59" smd circle
			(at 14.071092 20.150074)
			(size 0.4318 0.4318)
			(layers "F.Cu" "F.Mask" "F.Paste")
			(net "M_L_MA<4>")
		)
		(pad "DT61" smd circle
			(at 15.787878 20.150074)
			(size 0.4318 0.4318)
			(layers "F.Cu" "F.Mask" "F.Paste")
			(net "M_L_ALERT_N")
		)
		(pad "DT63" smd circle
			(at 17.504918 20.150074)
			(size 0.4318 0.4318)
			(layers "F.Cu" "F.Mask" "F.Paste")
			(net "M_K_MA<12>")
		)
		(pad "DT65" smd circle
			(at 19.221958 20.150074)
			(size 0.4318 0.4318)
			(layers "F.Cu" "F.Mask" "F.Paste")
			(net "GND")
		)
		(pad "DT67" smd circle
			(at 20.938998 20.150074)
			(size 0.4318 0.4318)
			(layers "F.Cu" "F.Mask" "F.Paste")
			(net "M_L_DQS_DP<17>")
		)
		(pad "DT69" smd circle
			(at 22.656038 20.150074)
			(size 0.4318 0.4318)
			(layers "F.Cu" "F.Mask" "F.Paste")
			(net "GND")
		)
		(pad "DT71" smd circle
			(at 24.373078 20.150074)
			(size 0.4318 0.4318)
			(layers "F.Cu" "F.Mask" "F.Paste")
			(net "TP_CPU1_RSVD_27")
		)
		(pad "DT73" smd circle
			(at 26.090118 20.150074)
			(size 0.4318 0.4318)
			(layers "F.Cu" "F.Mask" "F.Paste")
			(net "M_K_DQ<27>")
		)
		(pad "DT75" smd circle
			(at 27.806904 20.150074)
			(size 0.4318 0.4318)
			(layers "F.Cu" "F.Mask" "F.Paste")
			(net "M_K_DQS_DP<3>")
		)
		(pad "DT77" smd circle
			(at 29.523944 20.150074)
			(size 0.4318 0.4318)
			(layers "F.Cu" "F.Mask" "F.Paste")
			(net "M_K_DQ<29>")
		)
		(pad "DT79" smd circle
			(at 31.240984 20.150074)
			(size 0.4318 0.4318)
			(layers "F.Cu" "F.Mask" "F.Paste")
			(net "GND")
		)
		(pad "DT81" smd circle
			(at 32.958024 20.150074)
			(size 0.4318 0.4318)
			(layers "F.Cu" "F.Mask" "F.Paste")
			(net "M_K_DQ<18>")
		)
		(pad "DT83" smd circle
			(at 34.675064 20.150074)
			(size 0.4318 0.4318)
			(layers "F.Cu" "F.Mask" "F.Paste")
			(net "GND")
		)
		(pad "DT85" smd custom
			(at 36.392104 20.150074 270)
			(size 0.10795 0.10795)
			(layers "F.Cu" "F.Mask" "F.Paste")
			(net "GND")
			(options
				(clearance outline)
				(anchor circle)
			)
			(primitives
				(gr_poly
					(pts
						(arc
							(start 0.2159 -0.0381)
							(mid 0 -0.254)
							(end -0.2159 -0.0381)
						)
						(arc
							(start -0.2159 0.0381)
							(mid 0 0.254)
							(end 0.2159 0.0381)
						)
					)
					(width 0)
					(fill yes)
				)
			)
		)
		(pad "DU2" smd custom
			(at -36.392104 22.445726 90)
			(size 0.10795 0.10795)
			(layers "F.Cu" "F.Mask" "F.Paste")
			(net "TP_P3E_CPU1_PE1_RSR3_TXP<9>")
			(options
				(clearance outline)
				(anchor circle)
			)
			(primitives
				(gr_poly
					(pts
						(arc
							(start 0.2159 -0.0381)
							(mid 0 -0.254)
							(end -0.2159 -0.0381)
						)
						(arc
							(start -0.2159 0.0381)
							(mid 0 0.254)
							(end 0.2159 0.0381)
						)
					)
					(width 0)
					(fill yes)
				)
			)
		)
		(pad "DU4" smd circle
			(at -34.675064 22.445726)
			(size 0.4318 0.4318)
			(layers "F.Cu" "F.Mask" "F.Paste")
			(net "TP_P3E_CPU1_PE1_RSR3_TXP<10>")
		)
		(pad "DU6" smd circle
			(at -32.958024 22.445726)
			(size 0.4318 0.4318)
			(layers "F.Cu" "F.Mask" "F.Paste")
			(net "TP_P3E_CPU1_PE1_RSR3_TXN<11>")
		)
		(pad "DU8" smd circle
			(at -31.240984 22.445726)
			(size 0.4318 0.4318)
			(layers "F.Cu" "F.Mask" "F.Paste")
			(net "P3E_CPU1_PE3_MP_TXN<6>")
		)
		(pad "DU10" smd circle
			(at -29.523944 22.445726)
			(size 0.4318 0.4318)
			(layers "F.Cu" "F.Mask" "F.Paste")
			(net "GND")
		)
		(pad "DU12" smd circle
			(at -27.806904 22.445726)
			(size 0.4318 0.4318)
			(layers "F.Cu" "F.Mask" "F.Paste")
			(net "TP_P3E_CPU1_PE1_RSR3_RXP<12>")
		)
		(pad "DU14" smd circle
			(at -26.090118 22.445726)
			(size 0.4318 0.4318)
			(layers "F.Cu" "F.Mask" "F.Paste")
			(net "GND")
		)
		(pad "DU16" smd circle
			(at -24.373078 22.445726)
			(size 0.4318 0.4318)
			(layers "F.Cu" "F.Mask" "F.Paste")
			(net "TP_P3E_CPU1_PE1_RSR3_RXN<15>")
		)
		(pad "DU18" smd circle
			(at -22.656038 22.445726)
			(size 0.4318 0.4318)
			(layers "F.Cu" "F.Mask" "F.Paste")
			(net "P3E_CPU1_PE3_MP_RXP<1>")
		)
		(pad "DU20" smd circle
			(at -20.938998 22.445726)
			(size 0.4318 0.4318)
			(layers "F.Cu" "F.Mask" "F.Paste")
			(net "PVCCIO_CPU1")
		)
		(pad "DU22" smd circle
			(at -19.221958 22.445726)
			(size 0.4318 0.4318)
			(layers "F.Cu" "F.Mask" "F.Paste")
			(net "GND")
		)
		(pad "DU24" smd circle
			(at -17.504918 22.445726)
			(size 0.4318 0.4318)
			(layers "F.Cu" "F.Mask" "F.Paste")
			(net "M_K_DQ<57>")
		)
		(pad "DU26" smd circle
			(at -15.787878 22.445726)
			(size 0.4318 0.4318)
			(layers "F.Cu" "F.Mask" "F.Paste")
			(net "GND")
		)
		(pad "DU28" smd circle
			(at -14.071092 22.445726)
			(size 0.4318 0.4318)
			(layers "F.Cu" "F.Mask" "F.Paste")
			(net "M_K_DQ<55>")
		)
		(pad "DU30" smd circle
			(at -12.354052 22.445726)
			(size 0.4318 0.4318)
			(layers "F.Cu" "F.Mask" "F.Paste")
			(net "M_K_DQ<49>")
		)
		(pad "DU32" smd circle
			(at -10.637012 22.445726)
			(size 0.4318 0.4318)
			(layers "F.Cu" "F.Mask" "F.Paste")
			(net "GND")
		)
		(pad "DU34" smd circle
			(at -8.919972 22.445726)
			(size 0.4318 0.4318)
			(layers "F.Cu" "F.Mask" "F.Paste")
			(net "M_K_DQ<47>")
		)
	)
)
